FILE_TYPE = CONNECTIVITY;
{Allegro Design Entry HDL 16.6-p007 (v16-6-112F) 10/10/2012}
"PAGE_NUMBER" = 163;
0"NC";
1"GND\g";
2"GND\g";
3"P3V3_STBY\g";
4"P3V3_STBY\g";
5"PVCCIO_CPU1\g";
6"PVCCIO_CPU1\g";
7"SMB_CPU1_PE_HP_GTL_SDA";
8"SMB_CPU1_PE_HP_GTL_SCL";
9"SMB_CPU1_PE_HP_GTL_R_SCL";
10"SMB_CPU1_PE_HP_GTL_R_SDA";
11"TP_SMB_PEHPCPU1_EN";
12"SMB_PEHPCPU1_STBY_LVC3_R_SCL";
13"SMB_PEHPCPU1_STBY_LVC3_R_SDA";
14"SMB_SLOTX24_BMC_STBY_LVC3_SCL";
15"SMB_PEHPCPU1_STBY_LVC3_SCL";
16"SMB_SLOTX24_BMC_STBY_LVC3_SDA";
17"SMB_PEHPCPU1_STBY_LVC3_SDA";
%"PCA9517"
"1","(-1600,3250)","0","mstr_digital","I1";
;
CDS_SEC"1"
ROOM"SMB_PE_HP_CPU1"
SEC_TYPE"SM"
CDS_LIB"mstr_digital"
SEC"1"
CDS_LOCATION"U1B2"
PACK_TYPE"SM"
MATERIAL"IC"
PART_NUMBER"G77073-001"
LOCATION"U1B2"
POWER_GROUP"GND=GND";
"EN"
$PN"5"11;
"VCCB"
$PN"8"3;
"SDAB"
$PN"6"13;
"SCLB"
$PN"7"12;
"SDAA"
$PN"3"10;
"SCLA"
$PN"2"9;
"VCCA"
$PN"1"6;
%"CAP_A"
"1","(-1950,3825)","0","dev_discrete","I10";
;
CDS_SEC"1"
ROOM"SMB_PE_HP_CPU1"
SEC_TYPE"0402V"
SEC"1"
CDS_LIB"dev_discrete"
CDS_LOCATION"C9M8"
MATERIAL"X7R"
VOLTAGE"16V"
PACK_TYPE"0402V"
TOLERANCE"10%"
VALUE"0.1UF"
PART_NUMBER"A36096-030"
LOCATION"C9M8";
"B"
$PN"2"1;
"A"
$PN"1"6;
%"GND"
"1","(-1950,3600)","0","mstr_symbols","I11";
;
HDL_POWER"GND"
ROOM"P2V5_LAN_AUX_VR"
BODY_TYPE"PLUMBING"
BOM_COST"NT_BASE_VRD"
SIZE"1B"
CDS_LIB"mstr_symbols"
VOLTAGE"0";
"A\NAC"1;
%"CAP_A"
"1","(-1275,3825)","2","dev_discrete","I12";
;
CDS_SEC"1"
ROOM"SMB_PE_HP_CPU1"
CDS_LOCATION"C9M7"
CDS_LIB"dev_discrete"
SEC"1"
SEC_TYPE"0402V"
MATERIAL"X7R"
VOLTAGE"16V"
PACK_TYPE"0402V"
TOLERANCE"10%"
VALUE"0.1UF"
PART_NUMBER"A36096-030"
LOCATION"C9M7";
"B"
$PN"2"2;
"A"
$PN"1"3;
%"GND"
"1","(-1275,3600)","0","mstr_symbols","I13";
;
HDL_POWER"GND"
ROOM"P2V5_LAN_AUX_VR"
BODY_TYPE"PLUMBING"
BOM_COST"NT_BASE_VRD"
SIZE"1B"
CDS_LIB"mstr_symbols"
VOLTAGE"0";
"A\NAC"2;
%"RES"
"2","(-750,3650)","2","mstr_discrete","I15";
;
CDS_SEC"1"
ROOM"SMB_PE_HP_CPU1"
CDS_LIB"mstr_discrete"
SEC_TYPE"0402"
SEC"1"
CDS_LOCATION"R9M17"
WATTAGE"1/16W"
MATERIAL"CHIP"
PACK_TYPE"0402"
TOLERANCE"1%"
VALUE"2.0K"
PART_NUMBER"G21796-001"
LOCATION"R9M17";
"A"
$PN"1"4;
"B"
$PN"2"12;
%"RES"
"2","(-600,3650)","0","mstr_discrete","I16";
;
CDS_SEC"1"
ROOM"SMB_PE_HP_CPU1"
SEC_TYPE"0402"
CDS_LIB"mstr_discrete"
SEC"1"
CDS_LOCATION"R9M16"
WATTAGE"1/16W"
MATERIAL"CHIP"
PACK_TYPE"0402"
TOLERANCE"1%"
VALUE"2.0K"
PART_NUMBER"G21796-001"
LOCATION"R9M16";
"A"
$PN"1"4;
"B"
$PN"2"13;
%"RES"
"1","(-3950,3300)","0","mstr_discrete","I2";
;
CDS_SEC"1"
ROOM"CPU1"
SEC_TYPE"0402"
CDS_LIB"mstr_discrete"
SEC"1"
CDS_LOCATION"R6N8"
WATTAGE"1/16W"
MATERIAL"CHIP"
PACK_TYPE"0402"
TOLERANCE"1%"
VALUE"10.0"
PART_NUMBER"G21796-066"
LOCATION"R6N8";
"B"
$PN"2"9;
"A"
$PN"1"8;
%"RES"
"1","(-200,3300)","0","mstr_discrete","I20";
;
ROOM"SMB_PE_HP_CPU1"
CDS_LIB"mstr_discrete"
CDS_SEC"1"
$SEC"1"
CDS_LOCATION"R9M14"
WATTAGE"1/16W"
MATERIAL"CHIP"
PACK_TYPE"0402"
TOLERANCE"1%"
VALUE"20.0"
PART_NUMBER"G21796-173"
LOCATION"R9M14";
"B"
$PN"2"15;
"A"
$PN"1"12;
%"RES"
"1","(50,3250)","0","mstr_discrete","I21";
;
ROOM"SMB_PE_HP_CPU1"
CDS_LIB"mstr_discrete"
CDS_SEC"1"
$SEC"1"
CDS_LOCATION"R9M13"
WATTAGE"1/16W"
MATERIAL"CHIP"
PACK_TYPE"0402"
TOLERANCE"1%"
VALUE"20.0"
PART_NUMBER"G21796-173"
LOCATION"R9M13";
"B"
$PN"2"17;
"A"
$PN"1"13;
%"RES"
"1","(100,2825)","0","mstr_discrete","I24";
;
ROOM"SMB_PE_HP_CPU1"
CDS_LIB"mstr_discrete"
CDS_SEC"1"
$SEC"1"
CDS_LOCATION"R9M12"
WATTAGE"1/16W"
MATERIAL"CHIP"
PACK_TYPE"0402"
TOLERANCE"1%"
VALUE"20.0"
PART_NUMBER"G21796-173"
LOCATION"R9M12";
"B"
$PN"2"16;
"A"
$PN"1"13;
%"RES"
"1","(-150,2875)","0","mstr_discrete","I25";
;
ROOM"SMB_PE_HP_CPU1"
CDS_LIB"mstr_discrete"
CDS_SEC"1"
$SEC"1"
CDS_LOCATION"R9M15"
WATTAGE"1/16W"
MATERIAL"CHIP"
PACK_TYPE"0402"
TOLERANCE"1%"
VALUE"20.0"
PART_NUMBER"G21796-173"
LOCATION"R9M15";
"B"
$PN"2"14;
"A"
$PN"1"12;
%"P3V3_STBY"
"1","(-1200,4150)","0","mstr_symbols","I26";
;
HDL_POWER"P3V3_STBY"
BODY_TYPE"PLUMBING"
SIZE"1B"
CDS_LIB"mstr_symbols"
VOLTAGE"3.3V";
"G\NAC"3;
%"P3V3_STBY"
"1","(-675,4050)","0","mstr_symbols","I27";
;
HDL_POWER"P3V3_STBY"
BODY_TYPE"PLUMBING"
CDS_LIB"mstr_symbols"
SIZE"1B"
VOLTAGE"3.3V";
"G\NAC"4;
%"RES"
"1","(-3425,3250)","0","mstr_discrete","I3";
;
CDS_SEC"1"
ROOM"CPU1"
SEC_TYPE"0402"
CDS_LIB"mstr_discrete"
SEC"1"
CDS_LOCATION"R6N9"
WATTAGE"1/16W"
MATERIAL"CHIP"
PACK_TYPE"0402"
TOLERANCE"1%"
VALUE"10.0"
PART_NUMBER"G21796-066"
LOCATION"R6N9";
"B"
$PN"2"10;
"A"
$PN"1"7;
%"RES"
"2","(-2350,3650)","0","mstr_discrete","I6";
;
CDS_SEC"1"
ROOM"SMB_PE_HP_CPU1"
SEC_TYPE"0402"
CDS_LIB"mstr_discrete"
SEC"1"
CDS_LOCATION"R9M18"
WATTAGE"1/16W"
MATERIAL"CHIP"
PACK_TYPE"0402"
TOLERANCE"1.0%"
VALUE"240"
PART_NUMBER"G21796-294"
LOCATION"R9M18";
"A"
$PN"1"5;
"B"
$PN"2"10;
%"RES"
"2","(-2475,3650)","2","mstr_discrete","I7";
;
CDS_SEC"1"
ROOM"SMB_PE_HP_CPU1"
SEC_TYPE"0402"
CDS_LIB"mstr_discrete"
SEC"1"
CDS_LOCATION"R9M19"
WATTAGE"1/16W"
MATERIAL"CHIP"
PACK_TYPE"0402"
TOLERANCE"1.0%"
VALUE"240"
PART_NUMBER"G21796-294"
LOCATION"R9M19";
"A"
$PN"1"5;
"B"
$PN"2"9;
%"PVCCIO_CPU1"
"1","(-2400,4000)","0","mstr_symbols","I8";
;
HDL_POWER"PVCCIO_CPU1"
BODY_TYPE"PLUMBING"
CDS_LIB"mstr_symbols"
VOLTAGE"1.1V";
"G\NAC"5;
%"PVCCIO_CPU1"
"1","(-2025,4150)","0","mstr_symbols","I9";
;
HDL_POWER"PVCCIO_CPU1"
BODY_TYPE"PLUMBING"
CDS_LIB"mstr_symbols"
VOLTAGE"1.1V";
"G\NAC"6;
END.
